(kicad_pcb
	(version 20260206)
	(generator "pcbnew")
	(generator_version "10.0")
	(general
		(thickness 1.6)
		(legacy_teardrops no)
	)
	(paper "A4")
	(title_block
		(title "03242023_DA0F0TMBIJ0_F0T_Motherboard_J_brd_V01_OCP.brd")
		(comment 1 "Grand Teton / footprints 3891-3896 of 6105")
	)
	(layers
		(0 "F.Cu" signal "TOP")
		(4 "In1.Cu" signal "GND")
		(6 "In2.Cu" signal "IN1")
		(8 "In3.Cu" signal "GND1")
		(10 "In4.Cu" signal "IN2")
		(12 "In5.Cu" signal "GND2")
		(14 "In6.Cu" signal "IN3")
		(16 "In7.Cu" signal "GND3")
		(18 "In8.Cu" signal "VCC")
		(20 "In9.Cu" signal "VCC1")
		(22 "In10.Cu" signal "GND4")
		(24 "In11.Cu" signal "IN4")
		(26 "In12.Cu" signal "GND5")
		(28 "In13.Cu" signal "IN5")
		(30 "In14.Cu" signal "GND6")
		(32 "In15.Cu" signal "IN6")
		(34 "In16.Cu" signal "GND7")
		(2 "B.Cu" signal "BOTTOM")
		(9 "F.Adhes" user "F.Adhesive")
		(11 "B.Adhes" user "B.Adhesive")
		(13 "F.Paste" user "Package Geometry/Pastemask Top")
		(15 "B.Paste" user "Package Geometry/Pastemask Bottom")
		(5 "F.SilkS" user "Ref Des/Silkscreen Top")
		(7 "B.SilkS" user "Ref Des/Silkscreen Bottom")
		(1 "F.Mask" user "Board Geometry/Soldermask Top")
		(3 "B.Mask" user "Board Geometry/Soldermask Bottom")
		(17 "Dwgs.User" user "User.Drawings")
		(19 "Cmts.User" user "User.Comments")
		(21 "Eco1.User" user "User.Eco1")
		(23 "Eco2.User" user "User.Eco2")
		(25 "Edge.Cuts" user "Board Geometry/Outline")
		(27 "Margin" user)
		(31 "F.CrtYd" user "Package Geometry/Place Bound Top")
		(29 "B.CrtYd" user "Package Geometry/Place Bound Bottom")
		(35 "F.Fab" user "Ref Des/Assembly Top")
		(33 "B.Fab" user "Ref Des/Assembly Bottom")
	)
	(footprint ""
		(layer "F.Cu")
		(at 180.528468 -48.053498 180)
		(property "Reference" "C1100"
			(at 0 0 180)
			(layer "F.SilkS")
			(hide yes)
			(effects
				(font
					(size 1.27 1.27)
				)
			)
		)
		(property "Value" ""
			(at 0 0 180)
			(layer "F.Fab")
			(effects
				(font
					(size 1.27 1.27)
				)
			)
		)
		(duplicate_pad_numbers_are_jumpers no)
		(fp_line
			(start 0.299974 0.150114)
			(end -0.299974 0.150114)
			(stroke
				(width 0.1)
				(type default)
			)
			(layer "F.Fab")
		)
		(fp_line
			(start 0.299974 -0.150114)
			(end 0.299974 0.150114)
			(stroke
				(width 0.1)
				(type default)
			)
			(layer "F.Fab")
		)
		(fp_line
			(start -0.299974 0.150114)
			(end -0.299974 -0.150114)
			(stroke
				(width 0.1)
				(type default)
			)
			(layer "F.Fab")
		)
		(fp_line
			(start -0.299974 -0.150114)
			(end 0.299974 -0.150114)
			(stroke
				(width 0.1)
				(type default)
			)
			(layer "F.Fab")
		)
		(pad "1" smd rect
			(at -0.2667 0 180)
			(size 0.3048 0.381)
			(layers "F.Cu" "F.Mask" "F.Paste")
			(net "P3E_PCH_M2_TX_DP<2>")
		)
		(pad "2" smd rect
			(at 0.2667 0 180)
			(size 0.3048 0.381)
			(layers "F.Cu" "F.Mask" "F.Paste")
			(net "P3E_PCH_M2_TX_C_DP<2>")
		)
		(zone
			(layer "In1.Cu")
			(hatch none 0.5)
			(connect_pads
				(clearance 0)
			)
			(min_thickness 0.25)
			(keepout
				(tracks not_allowed)
				(vias allowed)
				(pads allowed)
				(copperpour not_allowed)
				(footprints allowed)
			)
			(placement
				(enabled no)
				(sheetname "")
			)
			(fill
				(thermal_gap 0.5)
				(thermal_bridge_width 0.5)
				(island_removal_mode 0)
			)
			(polygon
				(pts
					(arc
						(start 180.388768 -48.294798)
						(mid 180.44265 -48.27248)
						(end 180.464968 -48.218598)
					)
					(arc
						(start 180.464968 -47.888398)
						(mid 180.44265 -47.834516)
						(end 180.388768 -47.812198)
					)
					(arc
						(start 180.134768 -47.812198)
						(mid 180.080886 -47.834516)
						(end 180.058568 -47.888398)
					)
					(arc
						(start 180.058568 -48.218598)
						(mid 180.080886 -48.27248)
						(end 180.134768 -48.294798)
					)
				)
			)
		)
		(zone
			(layer "In1.Cu")
			(hatch none 0.5)
			(connect_pads
				(clearance 0)
			)
			(min_thickness 0.25)
			(keepout
				(tracks not_allowed)
				(vias allowed)
				(pads allowed)
				(copperpour not_allowed)
				(footprints allowed)
			)
			(placement
				(enabled no)
				(sheetname "")
			)
			(fill
				(thermal_gap 0.5)
				(thermal_bridge_width 0.5)
				(island_removal_mode 0)
			)
			(polygon
				(pts
					(arc
						(start 180.922168 -48.294798)
						(mid 180.97605 -48.27248)
						(end 180.998368 -48.218598)
					)
					(arc
						(start 180.998368 -47.888398)
						(mid 180.97605 -47.834516)
						(end 180.922168 -47.812198)
					)
					(arc
						(start 180.668168 -47.812198)
						(mid 180.614286 -47.834516)
						(end 180.591968 -47.888398)
					)
					(arc
						(start 180.591968 -48.218598)
						(mid 180.614286 -48.27248)
						(end 180.668168 -48.294798)
					)
				)
			)
		)
	)
	(footprint ""
		(layer "F.Cu")
		(at 365.46663 -240.276888 90)
		(property "Reference" "C1045"
			(at 0 0 90)
			(layer "F.SilkS")
			(hide yes)
			(effects
				(font
					(size 1.27 1.27)
				)
			)
		)
		(property "Value" ""
			(at 0 0 90)
			(layer "F.Fab")
			(effects
				(font
					(size 1.27 1.27)
				)
			)
		)
		(duplicate_pad_numbers_are_jumpers no)
		(fp_line
			(start 0.7874 -0.4064)
			(end 0.7874 0.4064)
			(stroke
				(width 0.1524)
				(type default)
			)
			(layer "F.SilkS")
		)
		(fp_line
			(start -0.7874 -0.4064)
			(end 0.7874 -0.4064)
			(stroke
				(width 0.1524)
				(type default)
			)
			(layer "F.SilkS")
		)
		(fp_line
			(start 0.7874 0.4064)
			(end -0.7874 0.4064)
			(stroke
				(width 0.1524)
				(type default)
			)
			(layer "F.SilkS")
		)
		(fp_line
			(start -0.7874 0.4064)
			(end -0.7874 -0.4064)
			(stroke
				(width 0.1524)
				(type default)
			)
			(layer "F.SilkS")
		)
		(fp_line
			(start -0.12065 -0.305054)
			(end -0.12065 -0.2794)
			(stroke
				(width 0.1)
				(type default)
			)
			(layer "F.Fab")
		)
		(fp_line
			(start -0.67945 -0.305054)
			(end -0.12065 -0.305054)
			(stroke
				(width 0.1)
				(type default)
			)
			(layer "F.Fab")
		)
		(fp_line
			(start 0.67945 -0.3048)
			(end 0.67945 0.3048)
			(stroke
				(width 0.1)
				(type default)
			)
			(layer "F.Fab")
		)
		(fp_line
			(start 0.12065 -0.3048)
			(end 0.67945 -0.3048)
			(stroke
				(width 0.1)
				(type default)
			)
			(layer "F.Fab")
		)
		(fp_line
			(start 0.12065 -0.2794)
			(end 0.12065 -0.3048)
			(stroke
				(width 0.1)
				(type default)
			)
			(layer "F.Fab")
		)
		(fp_line
			(start -0.12065 -0.2794)
			(end 0.12065 -0.2794)
			(stroke
				(width 0.1)
				(type default)
			)
			(layer "F.Fab")
		)
		(fp_line
			(start 0.120396 0.2794)
			(end -0.12065 0.2794)
			(stroke
				(width 0.1)
				(type default)
			)
			(layer "F.Fab")
		)
		(fp_line
			(start -0.12065 0.2794)
			(end -0.12065 0.3048)
			(stroke
				(width 0.1)
				(type default)
			)
			(layer "F.Fab")
		)
		(fp_line
			(start 0.67945 0.3048)
			(end 0.120396 0.3048)
			(stroke
				(width 0.1)
				(type default)
			)
			(layer "F.Fab")
		)
		(fp_line
			(start 0.120396 0.3048)
			(end 0.120396 0.2794)
			(stroke
				(width 0.1)
				(type default)
			)
			(layer "F.Fab")
		)
		(fp_line
			(start -0.12065 0.3048)
			(end -0.67945 0.3048)
			(stroke
				(width 0.1)
				(type default)
			)
			(layer "F.Fab")
		)
		(fp_line
			(start -0.67945 0.3048)
			(end -0.67945 -0.305054)
			(stroke
				(width 0.1)
				(type default)
			)
			(layer "F.Fab")
		)
		(pad "1" smd circle
			(at -0.40005 0 90)
			(size 0 0)
			(layers "F.Cu" "F.Mask" "F.Paste")
			(net "PVCCIN_CPU0")
		)
		(pad "2" smd circle
			(at 0.40005 0 90)
			(size 0 0)
			(layers "F.Cu" "F.Mask" "F.Paste")
			(net "GND")
		)
	)
	(footprint ""
		(layer "F.Cu")
		(at 5.35432 -74.719688)
		(property "Reference" "U241"
			(at -1.23698 2.420112 0)
			(unlocked yes)
			(layer "F.SilkS")
			(effects
				(font
					(size 0.7874 0.5842)
					(thickness 0.1524)
				)
				(justify left)
			)
		)
		(property "Value" ""
			(at 0 0 0)
			(layer "F.Fab")
			(effects
				(font
					(size 1.27 1.27)
				)
			)
		)
		(duplicate_pad_numbers_are_jumpers no)
		(fp_line
			(start -1.207008 -1.549908)
			(end -1.207008 1.549908)
			(stroke
				(width 0.1524)
				(type default)
			)
			(layer "F.SilkS")
		)
		(fp_line
			(start -1.207008 1.549908)
			(end 1.207008 1.549908)
			(stroke
				(width 0.1524)
				(type default)
			)
			(layer "F.SilkS")
		)
		(fp_line
			(start -0.762508 -1.549908)
			(end -1.207008 -1.549908)
			(stroke
				(width 0.1524)
				(type default)
			)
			(layer "F.SilkS")
		)
		(fp_line
			(start 0 -0.635)
			(end -0.762508 -1.549908)
			(stroke
				(width 0.1524)
				(type default)
			)
			(layer "F.SilkS")
		)
		(fp_line
			(start 0.762508 -1.549908)
			(end 0 -0.635)
			(stroke
				(width 0.1524)
				(type default)
			)
			(layer "F.SilkS")
		)
		(fp_line
			(start 1.207008 -1.549908)
			(end 0.762508 -1.549908)
			(stroke
				(width 0.1524)
				(type default)
			)
			(layer "F.SilkS")
		)
		(fp_line
			(start 1.207008 1.549908)
			(end 1.207008 -1.549908)
			(stroke
				(width 0.1524)
				(type default)
			)
			(layer "F.SilkS")
		)
		(fp_poly
			(pts
				(xy -3.48996 -1.64211) (xy -2.47396 -1.13411) (xy -3.48996 -0.62611)
			)
			(stroke
				(width 0)
				(type default)
			)
			(fill yes)
			(layer "F.SilkS")
		)
		(fp_line
			(start -1.549908 -1.549908)
			(end -1.549908 1.549908)
			(stroke
				(width 0.1)
				(type default)
			)
			(layer "F.Fab")
		)
		(fp_line
			(start -1.549908 1.549908)
			(end 1.549908 1.549908)
			(stroke
				(width 0.1)
				(type default)
			)
			(layer "F.Fab")
		)
		(fp_line
			(start 1.549908 -1.549908)
			(end -1.549908 -1.549908)
			(stroke
				(width 0.1)
				(type default)
			)
			(layer "F.Fab")
		)
		(fp_line
			(start 1.549908 1.549908)
			(end 1.549908 -1.549908)
			(stroke
				(width 0.1)
				(type default)
			)
			(layer "F.Fab")
		)
		(fp_poly
			(pts
				(xy -3.4036 -1.53289) (xy -3.4036 -0.51689) (xy -2.3876 -1.02489)
			)
			(stroke
				(width 0)
				(type default)
			)
			(fill yes)
			(layer "F.Fab")
		)
		(pad "1" smd rect
			(at -1.774952 -1.02489 270)
			(size 0.508 0.8636)
			(layers "F.Cu" "F.Mask" "F.Paste")
			(net "OCP_V3_2_PRSNT0_R_N")
		)
		(pad "2" smd rect
			(at -1.774952 -0.32512 270)
			(size 0.4064 0.8636)
			(layers "F.Cu" "F.Mask" "F.Paste")
			(net "OCP_V3_2_PRSNT1_R_N")
		)
		(pad "3" smd rect
			(at -1.774952 0.32512 270)
			(size 0.4064 0.8636)
			(layers "F.Cu" "F.Mask" "F.Paste")
			(net "OCP_V3_2_PRSNT23_R_N")
		)
		(pad "4" smd rect
			(at -1.774952 1.02489 270)
			(size 0.508 0.8636)
			(layers "F.Cu" "F.Mask" "F.Paste")
			(net "GND")
		)
		(pad "5" smd rect
			(at 1.774952 1.02489 270)
			(size 0.508 0.8636)
			(layers "F.Cu" "F.Mask" "F.Paste")
			(net "OCP_V3_2_PRSNT2_R_N")
		)
		(pad "6" smd rect
			(at 1.774952 0.32512 270)
			(size 0.4064 0.8636)
			(layers "F.Cu" "F.Mask" "F.Paste")
			(net "OCP_V3_2_PRSNT3_R_N")
		)
		(pad "7" smd rect
			(at 1.774952 -0.32512 270)
			(size 0.4064 0.8636)
			(layers "F.Cu" "F.Mask" "F.Paste")
			(net "OCP_V3_2_PRSNT01_R_N")
		)
		(pad "8" smd rect
			(at 1.774952 -1.02489 270)
			(size 0.508 0.8636)
			(layers "F.Cu" "F.Mask" "F.Paste")
			(net "P3V3_AUX")
		)
	)
	(footprint ""
		(layer "F.Cu")
		(at 70.052438 -31.887922 -90)
		(property "Reference" "R3630"
			(at 0 0 270)
			(layer "F.SilkS")
			(hide yes)
			(effects
				(font
					(size 1.27 1.27)
				)
			)
		)
		(property "Value" ""
			(at 0 0 270)
			(layer "F.Fab")
			(effects
				(font
					(size 1.27 1.27)
				)
			)
		)
		(duplicate_pad_numbers_are_jumpers no)
		(fp_line
			(start -0.7874 0.4064)
			(end -0.7874 -0.4064)
			(stroke
				(width 0.1524)
				(type default)
			)
			(layer "F.SilkS")
		)
		(fp_line
			(start 0.7874 0.4064)
			(end -0.7874 0.4064)
			(stroke
				(width 0.1524)
				(type default)
			)
			(layer "F.SilkS")
		)
		(fp_line
			(start -0.7874 -0.4064)
			(end 0.7874 -0.4064)
			(stroke
				(width 0.1524)
				(type default)
			)
			(layer "F.SilkS")
		)
		(fp_line
			(start 0.7874 -0.4064)
			(end 0.7874 0.4064)
			(stroke
				(width 0.1524)
				(type default)
			)
			(layer "F.SilkS")
		)
		(fp_line
			(start -0.67945 0.3048)
			(end -0.67945 -0.305054)
			(stroke
				(width 0.1)
				(type default)
			)
			(layer "F.Fab")
		)
		(fp_line
			(start -0.12065 0.3048)
			(end -0.67945 0.3048)
			(stroke
				(width 0.1)
				(type default)
			)
			(layer "F.Fab")
		)
		(fp_line
			(start 0.120396 0.3048)
			(end 0.120396 0.2794)
			(stroke
				(width 0.1)
				(type default)
			)
			(layer "F.Fab")
		)
		(fp_line
			(start 0.67945 0.3048)
			(end 0.120396 0.3048)
			(stroke
				(width 0.1)
				(type default)
			)
			(layer "F.Fab")
		)
		(fp_line
			(start -0.12065 0.2794)
			(end -0.12065 0.3048)
			(stroke
				(width 0.1)
				(type default)
			)
			(layer "F.Fab")
		)
		(fp_line
			(start 0.120396 0.2794)
			(end -0.12065 0.2794)
			(stroke
				(width 0.1)
				(type default)
			)
			(layer "F.Fab")
		)
		(fp_line
			(start -0.12065 -0.2794)
			(end 0.12065 -0.2794)
			(stroke
				(width 0.1)
				(type default)
			)
			(layer "F.Fab")
		)
		(fp_line
			(start 0.12065 -0.2794)
			(end 0.12065 -0.3048)
			(stroke
				(width 0.1)
				(type default)
			)
			(layer "F.Fab")
		)
		(fp_line
			(start 0.12065 -0.3048)
			(end 0.67945 -0.3048)
			(stroke
				(width 0.1)
				(type default)
			)
			(layer "F.Fab")
		)
		(fp_line
			(start 0.67945 -0.3048)
			(end 0.67945 0.3048)
			(stroke
				(width 0.1)
				(type default)
			)
			(layer "F.Fab")
		)
		(fp_line
			(start -0.67945 -0.305054)
			(end -0.12065 -0.305054)
			(stroke
				(width 0.1)
				(type default)
			)
			(layer "F.Fab")
		)
		(fp_line
			(start -0.12065 -0.305054)
			(end -0.12065 -0.2794)
			(stroke
				(width 0.1)
				(type default)
			)
			(layer "F.Fab")
		)
		(pad "1" smd circle
			(at -0.40005 0 270)
			(size 0 0)
			(layers "F.Cu" "F.Mask" "F.Paste")
			(net "HP_LVC3_OCP_V3_2_EN")
		)
		(pad "2" smd circle
			(at 0.40005 0 270)
			(size 0 0)
			(layers "F.Cu" "F.Mask" "F.Paste")
			(net "P12V_OCP_V3_2_EN_2_R3")
		)
	)
	(footprint ""
		(layer "F.Cu")
		(at 441.52566 -106.38536 -90)
		(property "Reference" "R4748"
			(at 0 0 270)
			(layer "F.SilkS")
			(hide yes)
			(effects
				(font
					(size 1.27 1.27)
				)
			)
		)
		(property "Value" ""
			(at 0 0 270)
			(layer "F.Fab")
			(effects
				(font
					(size 1.27 1.27)
				)
			)
		)
		(duplicate_pad_numbers_are_jumpers no)
		(fp_line
			(start -0.7874 0.4064)
			(end -0.7874 -0.4064)
			(stroke
				(width 0.1524)
				(type default)
			)
			(layer "F.SilkS")
		)
		(fp_line
			(start 0.7874 0.4064)
			(end -0.7874 0.4064)
			(stroke
				(width 0.1524)
				(type default)
			)
			(layer "F.SilkS")
		)
		(fp_line
			(start -0.7874 -0.4064)
			(end 0.7874 -0.4064)
			(stroke
				(width 0.1524)
				(type default)
			)
			(layer "F.SilkS")
		)
		(fp_line
			(start 0.7874 -0.4064)
			(end 0.7874 0.4064)
			(stroke
				(width 0.1524)
				(type default)
			)
			(layer "F.SilkS")
		)
		(fp_line
			(start -0.67945 0.3048)
			(end -0.67945 -0.305054)
			(stroke
				(width 0.1)
				(type default)
			)
			(layer "F.Fab")
		)
		(fp_line
			(start -0.12065 0.3048)
			(end -0.67945 0.3048)
			(stroke
				(width 0.1)
				(type default)
			)
			(layer "F.Fab")
		)
		(fp_line
			(start 0.120396 0.3048)
			(end 0.120396 0.2794)
			(stroke
				(width 0.1)
				(type default)
			)
			(layer "F.Fab")
		)
		(fp_line
			(start 0.67945 0.3048)
			(end 0.120396 0.3048)
			(stroke
				(width 0.1)
				(type default)
			)
			(layer "F.Fab")
		)
		(fp_line
			(start -0.12065 0.2794)
			(end -0.12065 0.3048)
			(stroke
				(width 0.1)
				(type default)
			)
			(layer "F.Fab")
		)
		(fp_line
			(start 0.120396 0.2794)
			(end -0.12065 0.2794)
			(stroke
				(width 0.1)
				(type default)
			)
			(layer "F.Fab")
		)
		(fp_line
			(start -0.12065 -0.2794)
			(end 0.12065 -0.2794)
			(stroke
				(width 0.1)
				(type default)
			)
			(layer "F.Fab")
		)
		(fp_line
			(start 0.12065 -0.2794)
			(end 0.12065 -0.3048)
			(stroke
				(width 0.1)
				(type default)
			)
			(layer "F.Fab")
		)
		(fp_line
			(start 0.12065 -0.3048)
			(end 0.67945 -0.3048)
			(stroke
				(width 0.1)
				(type default)
			)
			(layer "F.Fab")
		)
		(fp_line
			(start 0.67945 -0.3048)
			(end 0.67945 0.3048)
			(stroke
				(width 0.1)
				(type default)
			)
			(layer "F.Fab")
		)
		(fp_line
			(start -0.67945 -0.305054)
			(end -0.12065 -0.305054)
			(stroke
				(width 0.1)
				(type default)
			)
			(layer "F.Fab")
		)
		(fp_line
			(start -0.12065 -0.305054)
			(end -0.12065 -0.2794)
			(stroke
				(width 0.1)
				(type default)
			)
			(layer "F.Fab")
		)
		(pad "1" smd circle
			(at -0.40005 0 270)
			(size 0 0)
			(layers "F.Cu" "F.Mask" "F.Paste")
			(net "HP_LVC3_OCP_V3_1_PWRGD_R2")
		)
		(pad "2" smd circle
			(at 0.40005 0 270)
			(size 0 0)
			(layers "F.Cu" "F.Mask" "F.Paste")
			(net "OCP_SFF_AUX_PWR_EN_R2")
		)
	)
	(footprint ""
		(layer "F.Cu")
		(at 117.526816 -260.36524 -90)
		(property "Reference" "C441"
			(at 0 0 270)
			(layer "F.SilkS")
			(hide yes)
			(effects
				(font
					(size 1.27 1.27)
				)
			)
		)
		(property "Value" ""
			(at 0 0 270)
			(layer "F.Fab")
			(effects
				(font
					(size 1.27 1.27)
				)
			)
		)
		(duplicate_pad_numbers_are_jumpers no)
		(fp_line
			(start -0.7874 0.4064)
			(end -0.7874 -0.4064)
			(stroke
				(width 0.1524)
				(type default)
			)
			(layer "F.SilkS")
		)
		(fp_line
			(start 0.7874 0.4064)
			(end -0.7874 0.4064)
			(stroke
				(width 0.1524)
				(type default)
			)
			(layer "F.SilkS")
		)
		(fp_line
			(start -0.7874 -0.4064)
			(end 0.7874 -0.4064)
			(stroke
				(width 0.1524)
				(type default)
			)
			(layer "F.SilkS")
		)
		(fp_line
			(start 0.7874 -0.4064)
			(end 0.7874 0.4064)
			(stroke
				(width 0.1524)
				(type default)
			)
			(layer "F.SilkS")
		)
		(fp_line
			(start -0.67945 0.3048)
			(end -0.67945 -0.305054)
			(stroke
				(width 0.1)
				(type default)
			)
			(layer "F.Fab")
		)
		(fp_line
			(start -0.12065 0.3048)
			(end -0.67945 0.3048)
			(stroke
				(width 0.1)
				(type default)
			)
			(layer "F.Fab")
		)
		(fp_line
			(start 0.120396 0.3048)
			(end 0.120396 0.2794)
			(stroke
				(width 0.1)
				(type default)
			)
			(layer "F.Fab")
		)
		(fp_line
			(start 0.67945 0.3048)
			(end 0.120396 0.3048)
			(stroke
				(width 0.1)
				(type default)
			)
			(layer "F.Fab")
		)
		(fp_line
			(start -0.12065 0.2794)
			(end -0.12065 0.3048)
			(stroke
				(width 0.1)
				(type default)
			)
			(layer "F.Fab")
		)
		(fp_line
			(start 0.120396 0.2794)
			(end -0.12065 0.2794)
			(stroke
				(width 0.1)
				(type default)
			)
			(layer "F.Fab")
		)
		(fp_line
			(start -0.12065 -0.2794)
			(end 0.12065 -0.2794)
			(stroke
				(width 0.1)
				(type default)
			)
			(layer "F.Fab")
		)
		(fp_line
			(start 0.12065 -0.2794)
			(end 0.12065 -0.3048)
			(stroke
				(width 0.1)
				(type default)
			)
			(layer "F.Fab")
		)
		(fp_line
			(start 0.12065 -0.3048)
			(end 0.67945 -0.3048)
			(stroke
				(width 0.1)
				(type default)
			)
			(layer "F.Fab")
		)
		(fp_line
			(start 0.67945 -0.3048)
			(end 0.67945 0.3048)
			(stroke
				(width 0.1)
				(type default)
			)
			(layer "F.Fab")
		)
		(fp_line
			(start -0.67945 -0.305054)
			(end -0.12065 -0.305054)
			(stroke
				(width 0.1)
				(type default)
			)
			(layer "F.Fab")
		)
		(fp_line
			(start -0.12065 -0.305054)
			(end -0.12065 -0.2794)
			(stroke
				(width 0.1)
				(type default)
			)
			(layer "F.Fab")
		)
		(pad "1" smd circle
			(at -0.40005 0 270)
			(size 0 0)
			(layers "F.Cu" "F.Mask" "F.Paste")
			(net "PVCCFA_EHV_FIVRA_CPU1")
		)
		(pad "2" smd circle
			(at 0.40005 0 270)
			(size 0 0)
			(layers "F.Cu" "F.Mask" "F.Paste")
			(net "GND")
		)
	)
)
